FILE_TYPE = CONNECTIVITY;
{Allegro Design Entry HDL 16.6-p007 (v16-6-112F) 10/10/2012}
"PAGE_NUMBER" = 205;
0"NC";
1"PVSA_CPU0\g";
2"GND\g";
3"GND\g";
4"PVSA_CPU0\g";
5"GND\g";
6"VR_FET_SW_P12V_STBY_PVCCIN_CPU0\g";
7"GND\g";
8"PVSA_CPU0\g";
9"P5V_STBY\g";
10"GND\g";
11"GND\g";
12"GND\g";
13"GND\g";
14"GND\g";
15"VSENSE_PVSA_CPU0_P";
16"VR_PVSA_CPU0_PHASE"VOLTAGE"5";
17"VR_PVSA_CPU0_BIREF1";
18"VSENSE_PVSA_CPU0_SKT_VSEN";
19"VSENSE_PVSA_CPU0_SKT_VRTN";
20"TP_PVSA_CPU0_GL_1";
21"A_TSENSE_PVSA_CPU0";
22"VR_PVSA_CPU0_OCSET";
23"ISENSE_PVSA_CPU0_IMON";
24"TP_PVSA_CPU0_GL_0";
25"VR_PVSA_CPU0_BOOT_R";
26"VR_PVSA_CPU0_BOOT";
27"VSENSE_PVSA_CPU0_N";
28"VR_PVSA_CPU0_PHASE_SW_RC";
29"VR_PVSA_CPU0_PWM";
30"VR_PVSA_CPU0_VCIN"VOLTAGE"5";
31"VR_PVSA_CPU0_PHASE_SW"VOLTAGE"5";
%"PVSA_CPU0"
"1","(-2000,1600)","0","mstr_symbols","I11";
;
CDS_LIB"mstr_symbols"
VOLTAGE"1.1V"
BODY_TYPE"PLUMBING"
HDL_POWER"PVSA_CPU0";
"G\NAC"1;
%"CAPP"
"1","(-2000,1350)","0","mstr_discrete","I12";
;
CDS_SEC"1"
VOLTAGE"2.5V"
PART_NUMBER"699013-049"
LOCATION"C6N1"
VALUE"470UF"
TOLERANCE"20%"
GROUP"PWR_BULK_CAP"
PACK_TYPE"3018"
MATERIAL"ALUM"
CDS_LIB"mstr_discrete"
CDS_LOCATION"C6N1"
ROOM"PVSA_CPU0_DECAP_VR"
BOM_COST"PROC_VRD_VCCIN_CPU0"
SEC"1"
SEC_TYPE"3018";
"B"
$PN"2"2;
"A"
$PN"1"1;
%"GND"
"1","(-2000,975)","0","mstr_symbols","I13";
;
CDS_LIB"mstr_symbols"
SIZE"1B"
VOLTAGE"0"
BOM_COST"PROC_VRD_VCCIN_CPU0"
ROOM"PVSA_CPU0_DECAP_VR"
BODY_TYPE"PLUMBING"
HDL_POWER"GND";
"A\NAC"2;
%"CAPP"
"1","(-2650,1350)","2","mstr_discrete","I14";
;
CDS_SEC"1"
VOLTAGE"2.5V"
MATERIAL"ALUM"
PART_NUMBER"699013-049"
VALUE"470UF"
LOCATION"C6N4"
PACK_TYPE"3018"
TOLERANCE"20%"
GROUP"PWR_BULK_CAP"
BOM_COST"PROC_VRD_VCCIN_CPU0"
ROOM"PVSA_CPU0_DECAP_VR"
CDS_LIB"mstr_discrete"
CDS_LOCATION"C6N4"
SEC"1"
SEC_TYPE"3018";
"B"
$PN"2"2;
"A"
$PN"1"1;
%"GND"
"1","(-2475,3275)","0","mstr_symbols","I15";
;
ROOM"PVSA_CPU0_PWR_VR"
BOM_COST"PROC_VRD_VCCIN_CPU0"
SIZE"1B"
VOLTAGE"0"
CDS_LIB"mstr_symbols"
BODY_TYPE"PLUMBING"
HDL_POWER"GND";
"A\NAC"3;
%"CAP"
"1","(-5300,4200)","0","mstr_discrete","I16";
;
CDS_SEC"1"
LOCATION"C4C5"
VALUE"0.22UF"
MATERIAL"X7R"
VOLTAGE"16V"
PACK_TYPE"0402"
PART_NUMBER"A36096-155"
TOLERANCE"10%"
CDS_LIB"mstr_discrete"
SEC_TYPE"0402"
SEC"1"
CDS_LOCATION"C4C5"
ROOM"PVSA_CPU0_PWR_VR";
"A"
$PN"1"9;
"B"
$PN"2"7;
%"CAP"
"1","(-6000,4200)","0","mstr_discrete","I20";
;
CDS_SEC"1"
PACK_TYPE"0402"
PART_NUMBER"D97712-011"
TOLERANCE"10%"
VOLTAGE"16V"
MATERIAL"X6S"
VALUE"1.0UF"
LOCATION"C4C6"
ROOM"PVSA_CPU0_PWR_VR"
SEC"1"
SEC_TYPE"0402"
CDS_LIB"mstr_discrete"
CDS_LOCATION"C4C6";
"A"
$PN"1"30;
"B"
$PN"2"7;
%"PVSA_CPU0"
"1","(-4300,2650)","0","mstr_symbols","I23";
;
ROOM"PVSA_CPU0_VSENSE_VR"
CDS_LIB"mstr_symbols"
BOM_COST"PROC_VRD_VCCIN_CPU0"
VOLTAGE"1.1V"
BODY_TYPE"PLUMBING"
HDL_POWER"PVSA_CPU0";
"G\NAC"4;
%"RES"
"1","(-5100,2425)","0","mstr_discrete","I24";
;
CDS_SEC"1"
PART_NUMBER"G21796-017"
LOCATION"R4C5"
WATTAGE"1/16W"
PACK_TYPE"0402"
MATERIAL"CHIP"
TOLERANCE"1%"
VALUE"100.0"
CDS_LIB"mstr_discrete"
SEC_TYPE"0402"
SEC"1"
BOM_COST"PROC_VRD_VCCIN_CPU0"
ROOM"PVSA_CPU0_VSENSE_VR"
CDS_LOCATION"R4C5";
"B"
$PN"2"4;
"A"
$PN"1"15;
%"CAP"
"1","(-6050,3550)","2","mstr_discrete","I25";
;
CDS_SEC"1"
LOCATION"C4C8"
VALUE"0.220UF"
VOLTAGE"16V"
MATERIAL"X7R"
PART_NUMBER"A36096-104"
PACK_TYPE"0402"
TOLERANCE"10%"
SEC"1"
SEC_TYPE"0402"
SPOF"TRUE"
ROOM"PVSA_CPU0_PWR_VR"
CDS_LOCATION"C4C8"
CDS_LIB"mstr_discrete";
"A"
$PN"1"26;
"B"
$PN"2"16;
%"RES"
"1","(-5075,2025)","0","mstr_discrete","I26";
;
CDS_SEC"1"
MATERIAL"CHIP"
PACK_TYPE"0402"
WATTAGE"1/16W"
VALUE"0.0"
LOCATION"R4C4"
PART_NUMBER"G21497-005"
TOLERANCE"5%"
SEC"1"
SEC_TYPE"0402"
BOM_COST"PROC_VRD_VCCIN_CPU0"
CDS_LOCATION"R4C4"
ROOM"PVSA_CPU0_VSENSE_VR"
CDS_LIB"mstr_discrete";
"B"
$PN"2"18;
"A"
$PN"1"15;
%"GND"
"1","(-4250,1050)","0","mstr_symbols","I28";
;
CDS_LIB"mstr_symbols"
VOLTAGE"0"
BOM_COST"PROC_VRD_VCCIN_CPU0"
ROOM"PVSA_CPU0_VSENSE_VR"
SIZE"1B"
BODY_TYPE"PLUMBING"
HDL_POWER"GND";
"A\NAC"5;
%"RES"
"1","(-5075,1200)","0","mstr_discrete","I29";
;
CDS_SEC"1"
TOLERANCE"1%"
PACK_TYPE"0402"
PART_NUMBER"G21796-017"
WATTAGE"1/16W"
VALUE"100.0"
LOCATION"R4C1"
MATERIAL"CHIP"
SEC_TYPE"0402"
SEC"1"
CDS_LIB"mstr_discrete"
ROOM"PVSA_CPU0_VSENSE_VR"
CDS_LOCATION"R4C1"
BOM_COST"PROC_VRD_VCCIN_CPU0";
"B"
$PN"2"5;
"A"
$PN"1"27;
%"RES"
"1","(-5075,1575)","0","mstr_discrete","I30";
;
CDS_SEC"1"
PACK_TYPE"0402"
WATTAGE"1/16W"
PART_NUMBER"G21497-005"
LOCATION"R4C2"
MATERIAL"CHIP"
TOLERANCE"5%"
VALUE"0.0"
SEC_TYPE"0402"
SEC"1"
CDS_LIB"mstr_discrete"
ROOM"PVSA_CPU0_VSENSE_VR"
CDS_LOCATION"R4C2"
BOM_COST"PROC_VRD_VCCIN_CPU0";
"B"
$PN"2"19;
"A"
$PN"1"27;
%"CAP_A"
"1","(-6250,4200)","0","dev_discrete","I31";
;
VALUE"0.1UF"
LOCATION"C4C10"
PACK_TYPE"0402V"
MATERIAL"X7R"
TOLERANCE"10%"
VOLTAGE"16V"
PART_NUMBER"A36096-030"
SEC"1"
SEC_TYPE"0402V"
CDS_SEC"1"
CDS_LOCATION"C4C10"
ROOM"PVSA_CPU0_PWR_VR"
CDS_LIB"dev_discrete";
"B"
$PN"2"7;
"A"
$PN"1"6;
%"CAP"
"1","(-6475,4200)","0","mstr_discrete","I32";
;
CDS_SEC"1"
PART_NUMBER"D97712-011"
PACK_TYPE"0402"
MATERIAL"X6S"
VALUE"1.0UF"
VOLTAGE"16V"
TOLERANCE"10%"
LOCATION"C4C9"
CDS_LOCATION"C4C9"
CDS_LIB"mstr_discrete"
ROOM"PVSA_CPU0_PWR_VR"
SEC"1"
SEC_TYPE"0402";
"A"
$PN"1"6;
"B"
$PN"2"7;
%"CAP"
"1","(-6700,4200)","0","mstr_discrete","I33";
;
CDS_SEC"1"
MATERIAL"X6S"
VOLTAGE"16V"
VALUE"10UF"
TOLERANCE"10%"
PART_NUMBER"C95333-007"
LOCATION"C6N2"
PACK_TYPE"0805"
CDS_LIB"mstr_discrete"
CDS_LOCATION"C6N2"
ROOM"PVSA_CPU0_PWR_VR"
SEC"1"
SEC_TYPE"0805";
"A"
$PN"1"6;
"B"
$PN"2"7;
%"CAP"
"1","(-6925,4200)","0","mstr_discrete","I34";
;
CDS_SEC"1"
VOLTAGE"16V"
LOCATION"C6N3"
TOLERANCE"10%"
VALUE"10UF"
PACK_TYPE"0805"
PART_NUMBER"C95333-007"
MATERIAL"X6S"
CDS_LIB"mstr_discrete"
CDS_LOCATION"C6N3"
ROOM"PVSA_CPU0_PWR_VR"
SEC"1"
SEC_TYPE"0805";
"A"
$PN"1"6;
"B"
$PN"2"7;
%"CAP"
"1","(-7175,4200)","0","mstr_discrete","I35";
;
CDS_SEC"1"
VOLTAGE"16V"
TOLERANCE"10%"
VALUE"10UF"
LOCATION"C6N6"
MATERIAL"X6S"
PART_NUMBER"C95333-007"
PACK_TYPE"0805"
CDS_LIB"mstr_discrete"
ROOM"PVSA_CPU0_PWR_VR"
SEC_TYPE"0805"
SEC"1"
CDS_LOCATION"C6N6";
"A"
$PN"1"6;
"B"
$PN"2"7;
%"VCC_CORE"
"1","(-7175,4675)","0","mstr_symbols","I36";
;
HDL_POWER"VR_FET_SW_P12V_STBY_PVCCIN_CPU0"
CDS_LIB"mstr_symbols";
"A"6;
%"RES"
"2","(-5750,1825)","0","mstr_discrete","I37";
;
CDS_SEC"1"
LOCATION"R4C3"
VALUE"1.00K"
TOLERANCE"1%"
WATTAGE"1/16W"
MATERIAL"EMPTY"
PACK_TYPE"0402"
PART_NUMBER"G21796-026"
NO_XNET_CONNECTION"1"
SEC"1"
SEC_TYPE"0402"
BOM_COST"PROC_VRD_VCCIN_CPU0"
CDS_LOCATION"R4C3"
ROOM"PVSA_CPU0_VSENSE_VR"
CDS_LIB"mstr_discrete";
"A"
$PN"1"15;
"B"
$PN"2"27;
%"GND"
"1","(-6925,3725)","0","mstr_symbols","I39";
;
ROOM"PVSA_CPU0_PWR_VR"
BOM_COST"PROC_VRD_VCCIN_CPU0"
SIZE"1B"
CDS_LIB"mstr_symbols"
VOLTAGE"0"
BODY_TYPE"PLUMBING"
HDL_POWER"GND";
"A\NAC"7;
%"PVSA_CPU0"
"1","(-275,3725)","0","mstr_symbols","I4";
;
VOLTAGE"1.1V"
CDS_LIB"mstr_symbols"
BODY_TYPE"PLUMBING"
HDL_POWER"PVSA_CPU0";
"G\NAC"8;
%"P5V_STBY"
"1","(-4550,4850)","0","mstr_symbols","I42";
;
VOLTAGE"5.0V"
SIZE"1B"
CDS_LIB"mstr_symbols"
BODY_TYPE"PLUMBING"
HDL_POWER"P5V_STBY";
"G\NAC"9;
%"CAP_A"
"1","(-600,3075)","0","dev_discrete","I43";
;
LOCATION"C4C11"
VALUE"22.0UF"
VOLTAGE"4V"
TOLERANCE"20%"
MATERIAL"X6S"
PART_NUMBER"E15431-004"
PACK_TYPE"0603V"
CDS_LOCATION"C4C11"
CDS_LIB"dev_discrete"
CDS_SEC"1"
SEC_TYPE"0603V"
SEC"1";
"B"
$PN"2"10;
"A"
$PN"1"8;
%"RES"
"2","(-275,3075)","0","mstr_discrete","I45";
;
CDS_SEC"1"
LOCATION"R6N4"
VALUE"51.1"
TOLERANCE"1.0%"
WATTAGE"1/16W"
MATERIAL"CHIP"
PART_NUMBER"G21796-208"
PACK_TYPE"0402"
CDS_LOCATION"R6N4"
CDS_LIB"mstr_discrete"
SEC"1"
SEC_TYPE"0402";
"A"
$PN"1"8;
"B"
$PN"2"10;
%"IR354XX"
"1","(-3150,3925)","0","mstr_discrete","I46";
;
PART_NUMBER"H73684-001"
LOCATION"EU4C1"
MATERIAL"IC"
CDS_LIB"mstr_discrete"
CDS_LOCATION"EU4C1"
CDS_SEC"1"
$SEC"1"
PACK_TYPE"SM"
VALUE"IR35412";
"TOUT_FLT"
$PN"36"21;
"NC"
$PN"31"0;
"OCSET"
$PN"37"22;
"IOUT"
$PN"38"23;
"SW"
$PN"10"31;
"BOOST"
$PN"33"25;
"REFIN"
$PN"39"17;
"PWM"
$PN"34"29;
"PHASE"
$PN"32"16;
"VIN<0>"
$PN"25"6;
"VCC"
$PN"3"30;
"VIN<1>"
$PN"30"6;
"EN"
$PN"35"9;
"VDRV"
$PN"4"9;
"VOS"
$PN"1"8;
"LGND"
$PN"2"3;
"PGND<1>"
$PN"7"3;
"PGND<2>"
$PN"40"3;
"PGND<0>"
$PN"5"3;
"GL<0>"
$PN"6"24;
"GL<1>"
$PN"41"20;
%"CAP_A"
"1","(-950,3075)","0","dev_discrete","I5";
;
LOCATION"C6N7"
MATERIAL"X6S"
PACK_TYPE"0603V"
VALUE"22.0UF"
VOLTAGE"4V"
TOLERANCE"20%"
PART_NUMBER"E15431-004"
CDS_LIB"dev_discrete"
CDS_LOCATION"C6N7"
CDS_SEC"1"
ROOM"PVSA_CPU0_PWR_VR"
BOM_COST"PROC_VRD_VCCIN_CPU0"
SEC_TYPE"0603V"
SEC"1";
"B"
$PN"2"10;
"A"
$PN"1"8;
%"GND"
"1","(-275,2725)","0","mstr_symbols","I6";
;
ROOM"PVSA_CPU0_PWR_VR"
SIZE"1B"
CDS_LIB"mstr_symbols"
VOLTAGE"0"
BOM_COST"PROC_VRD_VCCIN_CPU0"
BODY_TYPE"PLUMBING"
HDL_POWER"GND";
"A\NAC"10;
%"RES"
"2","(-775,4100)","0","mstr_discrete","I62";
;
CDS_LOCATION"R4C13"
PACK_TYPE"0402"
LOCATION"R4C13"
VALUE"68.1K"
TOLERANCE"1%"
WATTAGE"1/16W"
MATERIAL"EMPTY"
PART_NUMBER"G21796-187"
CDS_LIB"mstr_discrete"
CDS_SEC"1"
$SEC"1";
"A"
$PN"1"22;
"B"
$PN"2"11;
%"GND"
"1","(-775,3825)","0","mstr_symbols","I63";
;
ROOM"PVSA_CPU1_PWR_VR"
SIZE"1B"
BOM_COST"PROC_VRD_VCCIN_CPU0"
CDS_LIB"mstr_symbols"
VOLTAGE"0"
BODY_TYPE"PLUMBING"
HDL_POWER"GND";
"A\NAC"11;
%"CAP"
"1","(-2025,3950)","0","mstr_discrete","I65";
;
CDS_SEC"1"
CDS_LOCATION"CT58"
LOCATION"CT58"
VALUE"1000PF"
VOLTAGE"50V"
TOLERANCE"10%"
MATERIAL"X7R"
PART_NUMBER"A36096-046"
PACK_TYPE"0402LF"
POP"NOPOP"
ROOM"VDDQ_KLM_PWR_VR"
CDS_LIB"mstr_discrete"
SEC"1"
SEC_TYPE"0402LF";
"A"
$PN"1"21;
"B"
$PN"2"12;
%"GND"
"1","(-2025,3750)","0","mstr_symbols","I66";
;
ROOM"VDDQ_KLM_PWR_VR"
VOLTAGE"0"
SIZE"1B"
CDS_LIB"mstr_symbols"
BODY_TYPE"PLUMBING"
HDL_POWER"GND";
"A\NAC"12;
%"GND"
"1","(-2050,2925)","0","mstr_symbols","I67";
;
ROOM"PVCCIN_CPU0_PWR_VR"
BOM_COST"PROC_VRD_VCCIN_CPU0"
VOLTAGE"0"
SIZE"1B"
CDS_LIB"mstr_symbols"
BODY_TYPE"PLUMBING"
HDL_POWER"GND";
"A\NAC"13;
%"CAP_A"
"1","(-3850,3425)","0","dev_discrete","I69";
;
CDS_SEC"1"
CDS_LOCATION"CT60"
VALUE"0.1UF"
TOLERANCE"10%"
MATERIAL"X7R"
PART_NUMBER"A36096-030"
PACK_TYPE"0402V"
LOCATION"CT60"
VOLTAGE"16V"
POP"NOPOP"
ROOM"PVCCIN_CPU0_PWR_VR"
CDS_LIB"dev_discrete"
SEC"1"
SEC_TYPE"0402V";
"B"
$PN"2"14;
"A"
$PN"1"17;
%"GND"
"1","(-3850,3175)","0","mstr_symbols","I70";
;
CDS_LIB"mstr_symbols"
VOLTAGE"0"
SIZE"1B"
BOM_COST"PROC_VRD_VCCIN_CPU0"
ROOM"PVCCIN_CPU0_PWR_VR"
BODY_TYPE"PLUMBING"
HDL_POWER"GND";
"A\NAC"14;
%"CAP"
"1","(-2050,3475)","0","mstr_discrete","I76";
;
CDS_SEC"1"
CDS_LOCATION"CT59"
VOLTAGE"50V"
MATERIAL"X7R"
TOLERANCE"10%"
POP"NOPOP"
LOCATION"CT59"
VALUE"1000PF"
PACK_TYPE"0402LF"
PART_NUMBER"A36096-046"
CDS_LIB"mstr_discrete"
ROOM"VDDQ_KLM_PWR_VR"
SEC"1"
SEC_TYPE"0402LF";
"A"
$PN"1"31;
"B"
$PN"2"28;
%"RES"
"1","(-5250,3700)","0","mstr_discrete","I78";
;
CDS_SEC"1"
CDS_LOCATION"RT40"
PACK_TYPE"0603"
VALUE"0"
PART_NUMBER"G22178-002"
TOLERANCE"5.0%"
WATTAGE"1/10W"
MATERIAL"CHIP"
LOCATION"RT40"
BOM_COST"NT_GBE_BASE"
ROOM"NIC_SPRV"
CDS_LIB"mstr_discrete"
SEC"1"
SEC_TYPE"0603";
"B"
$PN"2"25;
"A"
$PN"1"26;
%"RES"
"1","(-5850,4725)","0","mstr_discrete","I81";
;
MATERIAL"CHIP"
WATTAGE"1/16W"
PACK_TYPE"0402"
TOLERANCE"5%"
VALUE"0.0"
PART_NUMBER"G21497-005"
LOCATION"R6N3"
CDS_LOCATION"R6N3"
CDS_SEC"1"
ROOM"CPU0"
SEC"1"
SEC_TYPE"0402"
CDS_LIB"mstr_discrete"
BOM_COST"PROC_SIDEBAND";
"B"
$PN"2"9;
"A"
$PN"1"30;
%"IND-300NH-20-GP"
"1","(-1325,3650)","1","w_hdl","I82";
;
CDS_SEC"1"
CDS_LOCATION"L4C2"
TYPE"IRMS=66A@DELTA_T<40C"
PACK_SIZE"DCR=0.17MOHM"
RATED"ISAT=33A@25C"
ATTRIBUTE"300NH"
LOCATION"L4C2"
VALUE"IND-300NH-20-GP"
PART_NUMBER"068.3012N.M001"
CDS_LIB"w_hdl"
CDS_LMAN_SYM_OUTLINE"-75,100,75,-100"
SEC_TYPE"DISCRET-GB1"
SEC"1"
PACK_TYPE"DISCRET-GB1";
"F"
$PN"2"8;
"S"
$PN"1"31;
%"SC1U10V2KX-4-GP"
"1","(-5625,4175)","0","w_hdl","I83";
;
CDS_SEC"1"
CDS_LOCATION"C4C4"
PACK_SIZE"0402"
RATED"10V"
TOLERANCE"10%"
ATTRIBUTE"1UF"
VALUE"SC1U10V2KX-4-GP"
LOCATION"C4C4"
CDS_LMAN_SYM_OUTLINE"-50,25,50,-25"
CDS_LIB"w_hdl"
PART_NUMBER"78.10523.8FL"
SEC_TYPE"SMD-BCG6"
SEC"1"
PACK_TYPE"SMD-BCG6";
"2"
$PN"2"7;
"1"
$PN"1"9;
%"1R3F-GP"
"1","(-2050,3150)","0","w_hdl","I84";
;
CDS_SEC"1"
CDS_LOCATION"RT39"
LOCATION"RT39"
POP"NOPOP"
VALUE"1R3F-GP"
TOLERANCE"1%"
RATED"1/10W"
ATTRIBUTE"1 OHM"
PACK_SIZE"0603"
CDS_LMAN_SYM_OUTLINE"-50,75,50,-75"
CDS_LIB"w_hdl"
PART_NUMBER"64.1R005.55L"
SEC_TYPE"RCL_GP"
SEC"1"
PACK_TYPE"RCL_GP";
"2"
$PN"2"13;
"1"
$PN"1"28;
END.
